# BASEBOARD_FAB2 (Tioga Pass) — schematic netlist excerpt (pin names and nets, part order shuffled) for the footprints in the layout excerpt that follows; sources: Cadence DE-HDL packaged netlist, KiCad conversion of Wiwynn_Tioga_Pass_MB.brd

R6W44  RES  4.75K 1% CHIP  pkg 0402  page 164 : A = P3V3_STBY ; B = PCA9554_A0
R1D41  RES  0.0 5% CHIP  pkg 0805  page 199 : A = GND ; B = AGND_HSC
C7A6  CAP  1.0UF 16V 10% X6S  pkg 0402  page 236 : A = VR_PVNN_PCH_PH1_VCIN ; B = GND

(kicad_pcb
	(version 20260206)
	(generator "pcbnew")
	(generator_version "10.0")
	(general
		(thickness 1.6)
		(legacy_teardrops no)
	)
	(paper "A4")
	(title_block
		(title "Wiwynn_Tioga_Pass_MB.brd")
		(comment 1 "Tioga Pass / footprints 1585-1587 of 4770")
	)
	(layers
		(0 "F.Cu" signal "TOP")
		(4 "In1.Cu" signal "L2GND")
		(6 "In2.Cu" signal "L3")
		(8 "In3.Cu" signal "L4GND")
		(10 "In4.Cu" signal "L5")
		(12 "In5.Cu" signal "L6GND")
		(14 "In6.Cu" signal "L7VCC")
		(16 "In7.Cu" signal "L8VCC")
		(18 "In8.Cu" signal "L9GND")
		(20 "In9.Cu" signal "L10")
		(22 "In10.Cu" signal "L11GND")
		(24 "In11.Cu" signal "L12")
		(26 "In12.Cu" signal "L13GND")
		(2 "B.Cu" signal "BOTTOM")
		(9 "F.Adhes" user "F.Adhesive")
		(11 "B.Adhes" user "B.Adhesive")
		(13 "F.Paste" user "Package Geometry/Pastemask Top")
		(15 "B.Paste" user "Package Geometry/Pastemask Bottom")
		(5 "F.SilkS" user "Ref Des/Silkscreen Top")
		(7 "B.SilkS" user "Ref Des/Silkscreen Bottom")
		(1 "F.Mask" user "Board Geometry/Soldermask Top")
		(3 "B.Mask" user "Board Geometry/Soldermask Bottom")
		(17 "Dwgs.User" user "User.Drawings")
		(19 "Cmts.User" user "User.Comments")
		(21 "Eco1.User" user "User.Eco1")
		(23 "Eco2.User" user "User.Eco2")
		(25 "Edge.Cuts" user "Board Geometry/Outline")
		(27 "Margin" user)
		(31 "F.CrtYd" user "Package Geometry/Place Bound Top")
		(29 "B.CrtYd" user "Package Geometry/Place Bound Bottom")
		(35 "F.Fab" user "Ref Des/Assembly Top")
		(33 "B.Fab" user "Ref Des/Assembly Bottom")
	)
	(footprint ""
		(layer "F.Cu")
		(at 372.5672 -155.432506 180)
		(property "Reference" "C7A6"
			(at 0 0 180)
			(layer "F.SilkS")
			(hide yes)
			(effects
				(font
					(size 1.27 1.27)
				)
			)
		)
		(property "Value" ""
			(at 0 0 180)
			(layer "F.Fab")
			(effects
				(font
					(size 1.27 1.27)
				)
			)
		)
		(duplicate_pad_numbers_are_jumpers no)
		(fp_poly
			(pts
				(xy 0.3048 -0.1016) (xy 0.3048 0.9906) (xy -0.3048 0.9906) (xy -0.3048 -0.1016)
			)
			(stroke
				(width 0)
				(type default)
			)
			(fill no)
			(layer "F.CrtYd")
		)
		(fp_line
			(start 0.3048 0.9906)
			(end 0.3048 -0.1016)
			(stroke
				(width 0.1)
				(type default)
			)
			(layer "F.Fab")
		)
		(fp_line
			(start 0.3048 -0.1016)
			(end -0.3048 -0.1016)
			(stroke
				(width 0.1)
				(type default)
			)
			(layer "F.Fab")
		)
		(fp_line
			(start -0.3048 0.9906)
			(end 0.3048 0.9906)
			(stroke
				(width 0.1)
				(type default)
			)
			(layer "F.Fab")
		)
		(fp_line
			(start -0.3048 -0.1016)
			(end -0.3048 0.9906)
			(stroke
				(width 0.1)
				(type default)
			)
			(layer "F.Fab")
		)
		(pad "1" smd rect
			(at 0 0 180)
			(size 0.508 0.508)
			(layers "F.Cu" "F.Mask" "F.Paste")
			(net "VR_PVNN_PCH_PH1_VCIN")
		)
		(pad "2" smd rect
			(at 0 0.889 180)
			(size 0.508 0.508)
			(layers "F.Cu" "F.Mask" "F.Paste")
			(net "GND")
		)
		(zone
			(layer "F.Cu")
			(hatch none 0.5)
			(connect_pads
				(clearance 0)
			)
			(min_thickness 0.25)
			(keepout
				(tracks not_allowed)
				(vias allowed)
				(pads allowed)
				(copperpour not_allowed)
				(footprints allowed)
			)
			(placement
				(enabled no)
				(sheetname "")
			)
			(fill
				(thermal_gap 0.5)
				(thermal_bridge_width 0.5)
				(island_removal_mode 0)
			)
			(polygon
				(pts
					(xy 372.8212 -156.067506) (xy 372.3132 -156.067506) (xy 372.3132 -155.686506) (xy 372.8212 -155.686506)
				)
			)
		)
		(zone
			(layer "F.Cu")
			(hatch none 0.5)
			(connect_pads
				(clearance 0)
			)
			(min_thickness 0.25)
			(keepout
				(tracks allowed)
				(vias not_allowed)
				(pads allowed)
				(copperpour not_allowed)
				(footprints allowed)
			)
			(placement
				(enabled no)
				(sheetname "")
			)
			(fill
				(thermal_gap 0.5)
				(thermal_bridge_width 0.5)
				(island_removal_mode 0)
			)
			(polygon
				(pts
					(xy 372.8212 -155.686506) (xy 372.3132 -155.686506) (xy 372.3132 -156.067506) (xy 372.8212 -156.067506)
				)
			)
		)
	)
	(footprint ""
		(layer "F.Cu")
		(at 13.4366 -72.009 180)
		(property "Reference" "R1D41"
			(at 0 0 180)
			(layer "F.SilkS")
			(hide yes)
			(effects
				(font
					(size 1.27 1.27)
				)
			)
		)
		(property "Value" ""
			(at 0 0 180)
			(layer "F.Fab")
			(effects
				(font
					(size 1.27 1.27)
				)
			)
		)
		(duplicate_pad_numbers_are_jumpers no)
		(fp_poly
			(pts
				(xy -0.7239 -0.2159) (xy 0.7239 -0.2159) (xy 0.7239 1.9939) (xy -0.7239 1.9939)
			)
			(stroke
				(width 0)
				(type default)
			)
			(fill no)
			(layer "F.CrtYd")
		)
		(fp_line
			(start 0.7239 1.9939)
			(end 0.7239 -0.2159)
			(stroke
				(width 0.1)
				(type default)
			)
			(layer "F.Fab")
		)
		(fp_line
			(start 0.7239 -0.2159)
			(end -0.7239 -0.2159)
			(stroke
				(width 0.1)
				(type default)
			)
			(layer "F.Fab")
		)
		(fp_line
			(start -0.7239 1.9939)
			(end 0.7239 1.9939)
			(stroke
				(width 0.1)
				(type default)
			)
			(layer "F.Fab")
		)
		(fp_line
			(start -0.7239 -0.2159)
			(end -0.7239 1.9939)
			(stroke
				(width 0.1)
				(type default)
			)
			(layer "F.Fab")
		)
		(pad "1" smd rect
			(at 0 0 180)
			(size 1.27 1.016)
			(layers "F.Cu" "F.Mask" "F.Paste")
			(net "GND")
		)
		(pad "2" smd rect
			(at 0 1.778 180)
			(size 1.27 1.016)
			(layers "F.Cu" "F.Mask" "F.Paste")
			(net "AGND_HSC")
		)
		(zone
			(layer "F.Cu")
			(hatch none 0.5)
			(connect_pads
				(clearance 0)
			)
			(min_thickness 0.25)
			(keepout
				(tracks not_allowed)
				(vias allowed)
				(pads allowed)
				(copperpour not_allowed)
				(footprints allowed)
			)
			(placement
				(enabled no)
				(sheetname "")
			)
			(fill
				(thermal_gap 0.5)
				(thermal_bridge_width 0.5)
				(island_removal_mode 0)
			)
			(polygon
				(pts
					(xy 12.8016 -72.517) (xy 12.8016 -73.279) (xy 12.8905 -73.279) (xy 14.0716 -73.279) (xy 14.0716 -72.517)
				)
			)
		)
	)
	(footprint ""
		(layer "F.Cu")
		(at 433.9336 -16.0528 -90)
		(property "Reference" "R6W44"
			(at -0.8382 -0.67818 270)
			(unlocked yes)
			(layer "F.SilkS")
			(effects
				(font
					(size 0.4064 0.254)
					(thickness 0.1524)
				)
				(justify left)
			)
		)
		(property "Value" ""
			(at 0 0 270)
			(layer "F.Fab")
			(effects
				(font
					(size 1.27 1.27)
				)
			)
		)
		(duplicate_pad_numbers_are_jumpers no)
		(fp_poly
			(pts
				(xy -0.2794 -0.1016) (xy 0.2794 -0.1016) (xy 0.2794 0.9906) (xy -0.2794 0.9906)
			)
			(stroke
				(width 0)
				(type default)
			)
			(fill no)
			(layer "F.CrtYd")
		)
		(fp_line
			(start -0.2794 0.9906)
			(end 0.2794 0.9906)
			(stroke
				(width 0.1)
				(type default)
			)
			(layer "F.Fab")
		)
		(fp_line
			(start 0.2794 0.9906)
			(end 0.2794 -0.1016)
			(stroke
				(width 0.1)
				(type default)
			)
			(layer "F.Fab")
		)
		(fp_line
			(start -0.2794 -0.1016)
			(end -0.2794 0.9906)
			(stroke
				(width 0.1)
				(type default)
			)
			(layer "F.Fab")
		)
		(fp_line
			(start 0.2794 -0.1016)
			(end -0.2794 -0.1016)
			(stroke
				(width 0.1)
				(type default)
			)
			(layer "F.Fab")
		)
		(pad "1" smd rect
			(at 0 0 270)
			(size 0.508 0.508)
			(layers "F.Cu" "F.Mask" "F.Paste")
			(net "P3V3_STBY")
		)
		(pad "2" smd rect
			(at 0 0.889 270)
			(size 0.508 0.508)
			(layers "F.Cu" "F.Mask" "F.Paste")
			(net "PCA9554_A0")
		)
		(zone
			(layer "F.Cu")
			(hatch none 0.5)
			(connect_pads
				(clearance 0)
			)
			(min_thickness 0.25)
			(keepout
				(tracks not_allowed)
				(vias allowed)
				(pads allowed)
				(copperpour not_allowed)
				(footprints allowed)
			)
			(placement
				(enabled no)
				(sheetname "")
			)
			(fill
				(thermal_gap 0.5)
				(thermal_bridge_width 0.5)
				(island_removal_mode 0)
			)
			(polygon
				(pts
					(xy 433.2986 -16.3068) (xy 433.2986 -15.7988) (xy 433.6796 -15.7988) (xy 433.6796 -16.3068)
				)
			)
		)
		(zone
			(layer "F.Cu")
			(hatch none 0.5)
			(connect_pads
				(clearance 0)
			)
			(min_thickness 0.25)
			(keepout
				(tracks allowed)
				(vias not_allowed)
				(pads allowed)
				(copperpour not_allowed)
				(footprints allowed)
			)
			(placement
				(enabled no)
				(sheetname "")
			)
			(fill
				(thermal_gap 0.5)
				(thermal_bridge_width 0.5)
				(island_removal_mode 0)
			)
			(polygon
				(pts
					(xy 433.6796 -16.3068) (xy 433.6796 -15.7988) (xy 433.2986 -15.7988) (xy 433.2986 -16.3068)
				)
			)
		)
	)
)
